(kicad_pcb
	(version 20260206)
	(generator "pcbnew")
	(generator_version "10.0")
	(general
		(thickness 1.6)
		(legacy_teardrops no)
	)
	(paper "A4")
	(title_block
		(title "baseboard — 13948-1b.1110WZS1818.brd")
		(comment 1 "Honey Badger (Wiwynn) / footprint 1028 of 2523 (U40), pads 226-344 of 408")
	)
	(layers
		(0 "F.Cu" signal "TOP")
		(4 "In1.Cu" signal "L2GND")
		(6 "In2.Cu" signal "L3")
		(8 "In3.Cu" signal "L4VCC")
		(10 "In4.Cu" signal "L5VCC")
		(12 "In5.Cu" signal "L6")
		(14 "In6.Cu" signal "L7GND")
		(2 "B.Cu" signal "BOTTOM")
		(9 "F.Adhes" user "F.Adhesive")
		(11 "B.Adhes" user "B.Adhesive")
		(13 "F.Paste" user "Package Geometry/Pastemask Top")
		(15 "B.Paste" user "Package Geometry/Pastemask Bottom")
		(5 "F.SilkS" user "Ref Des/Silkscreen Top")
		(7 "B.SilkS" user "Ref Des/Silkscreen Bottom")
		(1 "F.Mask" user "Board Geometry/Soldermask Top")
		(3 "B.Mask" user "Board Geometry/Soldermask Bottom")
		(17 "Dwgs.User" user "User.Drawings")
		(19 "Cmts.User" user "User.Comments")
		(21 "Eco1.User" user "User.Eco1")
		(23 "Eco2.User" user "User.Eco2")
		(25 "Edge.Cuts" user "Board Geometry/Outline")
		(27 "Margin" user)
		(31 "F.CrtYd" user "Package Geometry/Place Bound Top")
		(29 "B.CrtYd" user "Package Geometry/Place Bound Bottom")
		(35 "F.Fab" user "Ref Des/Assembly Top")
		(33 "B.Fab" user "Ref Des/Assembly Bottom")
	)
	(footprint ""
		(layer "F.Cu")
		(at 293.234872 -175.840136 180)
		(property "Reference" "U40"
			(at 0 0 180)
			(layer "F.SilkS")
			(hide yes)
			(effects
				(font
					(size 1.27 1.27)
				)
			)
		)
		(property "Value" "AST1250A1-GP"
			(at -17.7292 -6.184392 180)
			(unlocked yes)
			(layer "F.Fab")
			(hide yes)
			(effects
				(font
					(size 1.016 1.016)
					(thickness 0.1524)
				)
			)
		)
		(property "Device Type" "BGA408D19H52"
			(at -17.7292 -7.708392 180)
			(unlocked yes)
			(layer "F.Fab")
			(hide yes)
			(effects
				(font
					(size 1.016 1.016)
					(thickness 0.1524)
				)
			)
		)
		(duplicate_pad_numbers_are_jumpers no)
		(pad "K18" smd circle
			(at 5.199888 -1.199896 180)
			(size 0.3556 0.3556)
			(layers "F.Cu" "F.Mask" "F.Paste")
			(net "ROMA23")
		)
		(pad "K19" smd circle
			(at 5.999988 -1.199896 180)
			(size 0.3556 0.3556)
			(layers "F.Cu" "F.Mask" "F.Paste")
			(net "PD_PERST_N")
		)
		(pad "K20" smd circle
			(at 6.800088 -1.199896 180)
			(size 0.3556 0.3556)
			(layers "F.Cu" "F.Mask" "F.Paste")
			(net "MB0_PRESNET#")
		)
		(pad "K21" smd circle
			(at 7.599934 -1.199896 180)
			(size 0.3556 0.3556)
			(layers "F.Cu" "F.Mask" "F.Paste")
			(net "BMC0_SMB1_CLK")
		)
		(pad "K22" smd circle
			(at 8.400034 -1.199896 180)
			(size 0.3556 0.3556)
			(layers "F.Cu" "F.Mask" "F.Paste")
			(net "BMC0_SMB1_DAT")
		)
		(pad "L1" smd circle
			(at -8.400034 -0.40005 180)
			(size 0.3556 0.3556)
			(layers "F.Cu" "F.Mask" "F.Paste")
			(net "ADC_P1V5_C_BMC")
		)
		(pad "L2" smd circle
			(at -7.599934 -0.40005 180)
			(size 0.3556 0.3556)
			(layers "F.Cu" "F.Mask" "F.Paste")
			(net "ADC_P1V8_STBY_BMC")
		)
		(pad "L3" smd circle
			(at -6.800088 -0.40005 180)
			(size 0.3556 0.3556)
			(layers "F.Cu" "F.Mask" "F.Paste")
			(net "ADC_P3V3_STBY_BMC")
		)
		(pad "L4" smd circle
			(at -5.999988 -0.40005 180)
			(size 0.3556 0.3556)
			(layers "F.Cu" "F.Mask" "F.Paste")
			(net "ADC_P5V_STBY_BMC")
		)
		(pad "L5" smd circle
			(at -5.199888 -0.40005 180)
			(size 0.3556 0.3556)
			(layers "F.Cu" "F.Mask" "F.Paste")
			(net "ADC0_12V_BMC")
		)
		(pad "L6" smd circle
			(at -4.400042 -0.40005 180)
			(size 0.3556 0.3556)
			(layers "F.Cu" "F.Mask" "F.Paste")
			(net "P1V26_STBY")
		)
		(pad "L9" smd circle
			(at -1.999996 -0.40005 180)
			(size 0.3556 0.3556)
			(layers "F.Cu" "F.Mask" "F.Paste")
			(net "GND")
		)
		(pad "L10" smd circle
			(at -1.199896 -0.40005 180)
			(size 0.3556 0.3556)
			(layers "F.Cu" "F.Mask" "F.Paste")
			(net "GND")
		)
		(pad "L11" smd circle
			(at -0.40005 -0.40005 180)
			(size 0.3556 0.3556)
			(layers "F.Cu" "F.Mask" "F.Paste")
			(net "GND")
		)
		(pad "L12" smd circle
			(at 0.40005 -0.40005 180)
			(size 0.3556 0.3556)
			(layers "F.Cu" "F.Mask" "F.Paste")
			(net "GND")
		)
		(pad "L13" smd circle
			(at 1.199896 -0.40005 180)
			(size 0.3556 0.3556)
			(layers "F.Cu" "F.Mask" "F.Paste")
			(net "GND")
		)
		(pad "L14" smd circle
			(at 1.999996 -0.40005 180)
			(size 0.3556 0.3556)
			(layers "F.Cu" "F.Mask" "F.Paste")
			(net "GND")
		)
		(pad "L17" smd circle
			(at 4.400042 -0.40005 180)
			(size 0.3556 0.3556)
			(layers "F.Cu" "F.Mask" "F.Paste")
			(net "P1V26_STBY")
		)
		(pad "L18" smd circle
			(at 5.199888 -0.40005 180)
			(size 0.3556 0.3556)
			(layers "F.Cu" "F.Mask" "F.Paste")
			(net "ROMA12")
		)
		(pad "L19" smd circle
			(at 5.999988 -0.40005 180)
			(size 0.3556 0.3556)
			(layers "F.Cu" "F.Mask" "F.Paste")
			(net "ROMA13")
		)
		(pad "L20" smd circle
			(at 6.800088 -0.40005 180)
			(size 0.3556 0.3556)
			(layers "F.Cu" "F.Mask" "F.Paste")
			(net "ROMA14")
		)
		(pad "L21" smd circle
			(at 7.599934 -0.40005 180)
			(size 0.3556 0.3556)
			(layers "F.Cu" "F.Mask" "F.Paste")
			(net "ROMA15")
		)
		(pad "L22" smd circle
			(at 8.400034 -0.40005 180)
			(size 0.3556 0.3556)
			(layers "F.Cu" "F.Mask" "F.Paste")
			(net "ROMA22")
		)
		(pad "M1" smd circle
			(at -8.400034 0.40005 180)
			(size 0.3556 0.3556)
			(layers "F.Cu" "F.Mask" "F.Paste")
			(net "GND")
		)
		(pad "M2" smd circle
			(at -7.599934 0.40005 180)
			(size 0.3556 0.3556)
			(layers "F.Cu" "F.Mask" "F.Paste")
			(net "GND")
		)
		(pad "M3" smd circle
			(at -6.800088 0.40005 180)
			(size 0.3556 0.3556)
			(layers "F.Cu" "F.Mask" "F.Paste")
			(net "ADC_P1V5_E_BMC")
		)
		(pad "M4" smd circle
			(at -5.999988 0.40005 180)
			(size 0.3556 0.3556)
			(layers "F.Cu" "F.Mask" "F.Paste")
			(net "ADC_P0V9_E_BMC")
		)
		(pad "M5" smd circle
			(at -5.199888 0.40005 180)
			(size 0.3556 0.3556)
			(layers "F.Cu" "F.Mask" "F.Paste")
			(net "ADC_P0V955_C_BMC")
		)
		(pad "M6" smd circle
			(at -4.400042 0.40005 180)
			(size 0.3556 0.3556)
			(layers "F.Cu" "F.Mask" "F.Paste")
			(net "P3V3_STBY")
		)
		(pad "M9" smd circle
			(at -1.999996 0.40005 180)
			(size 0.3556 0.3556)
			(layers "F.Cu" "F.Mask" "F.Paste")
			(net "GND")
		)
		(pad "M10" smd circle
			(at -1.199896 0.40005 180)
			(size 0.3556 0.3556)
			(layers "F.Cu" "F.Mask" "F.Paste")
			(net "GND")
		)
		(pad "M11" smd circle
			(at -0.40005 0.40005 180)
			(size 0.3556 0.3556)
			(layers "F.Cu" "F.Mask" "F.Paste")
			(net "GND")
		)
		(pad "M12" smd circle
			(at 0.40005 0.40005 180)
			(size 0.3556 0.3556)
			(layers "F.Cu" "F.Mask" "F.Paste")
			(net "GND")
		)
		(pad "M13" smd circle
			(at 1.199896 0.40005 180)
			(size 0.3556 0.3556)
			(layers "F.Cu" "F.Mask" "F.Paste")
			(net "GND")
		)
		(pad "M14" smd circle
			(at 1.999996 0.40005 180)
			(size 0.3556 0.3556)
			(layers "F.Cu" "F.Mask" "F.Paste")
			(net "GND")
		)
		(pad "M17" smd circle
			(at 4.400042 0.40005 180)
			(size 0.3556 0.3556)
			(layers "F.Cu" "F.Mask" "F.Paste")
			(net "P3V3_STBY")
		)
		(pad "M18" smd circle
			(at 5.199888 0.40005 180)
			(size 0.3556 0.3556)
			(layers "F.Cu" "F.Mask" "F.Paste")
			(net "ROMA19")
		)
		(pad "M19" smd circle
			(at 5.999988 0.40005 180)
			(size 0.3556 0.3556)
			(layers "F.Cu" "F.Mask" "F.Paste")
			(net "ROMA8")
		)
		(pad "M20" smd circle
			(at 6.800088 0.40005 180)
			(size 0.3556 0.3556)
			(layers "F.Cu" "F.Mask" "F.Paste")
			(net "ROMA9")
		)
		(pad "M21" smd circle
			(at 7.599934 0.40005 180)
			(size 0.3556 0.3556)
			(layers "F.Cu" "F.Mask" "F.Paste")
			(net "ROMA10")
		)
		(pad "M22" smd circle
			(at 8.400034 0.40005 180)
			(size 0.3556 0.3556)
			(layers "F.Cu" "F.Mask" "F.Paste")
			(net "ROMA11")
		)
		(pad "N1" smd circle
			(at -8.400034 1.199896 180)
			(size 0.3556 0.3556)
			(layers "F.Cu" "F.Mask" "F.Paste")
			(net "GND")
		)
		(pad "N2" smd circle
			(at -7.599934 1.199896 180)
			(size 0.3556 0.3556)
			(layers "F.Cu" "F.Mask" "F.Paste")
			(net "GND")
		)
		(pad "N3" smd circle
			(at -6.800088 1.199896 180)
			(size 0.3556 0.3556)
			(layers "F.Cu" "F.Mask" "F.Paste")
			(net "GND")
		)
		(pad "N4" smd circle
			(at -5.999988 1.199896 180)
			(size 0.3556 0.3556)
			(layers "F.Cu" "F.Mask" "F.Paste")
			(net "GND")
		)
		(pad "N5" smd circle
			(at -5.199888 1.199896 180)
			(size 0.3556 0.3556)
			(layers "F.Cu" "F.Mask" "F.Paste")
			(net "GND")
		)
		(pad "N6" smd circle
			(at -4.400042 1.199896 180)
			(size 0.3556 0.3556)
			(layers "F.Cu" "F.Mask" "F.Paste")
			(net "P3V3_STBY")
		)
		(pad "N9" smd circle
			(at -1.999996 1.199896 180)
			(size 0.3556 0.3556)
			(layers "F.Cu" "F.Mask" "F.Paste")
			(net "GND")
		)
		(pad "N10" smd circle
			(at -1.199896 1.199896 180)
			(size 0.3556 0.3556)
			(layers "F.Cu" "F.Mask" "F.Paste")
			(net "GND")
		)
		(pad "N11" smd circle
			(at -0.40005 1.199896 180)
			(size 0.3556 0.3556)
			(layers "F.Cu" "F.Mask" "F.Paste")
			(net "GND")
		)
		(pad "N12" smd circle
			(at 0.40005 1.199896 180)
			(size 0.3556 0.3556)
			(layers "F.Cu" "F.Mask" "F.Paste")
			(net "GND")
		)
		(pad "N13" smd circle
			(at 1.199896 1.199896 180)
			(size 0.3556 0.3556)
			(layers "F.Cu" "F.Mask" "F.Paste")
			(net "GND")
		)
		(pad "N14" smd circle
			(at 1.999996 1.199896 180)
			(size 0.3556 0.3556)
			(layers "F.Cu" "F.Mask" "F.Paste")
			(net "GND")
		)
		(pad "N17" smd circle
			(at 4.400042 1.199896 180)
			(size 0.3556 0.3556)
			(layers "F.Cu" "F.Mask" "F.Paste")
			(net "P3V3_STBY")
		)
		(pad "N18" smd circle
			(at 5.199888 1.199896 180)
			(size 0.3556 0.3556)
			(layers "F.Cu" "F.Mask" "F.Paste")
			(net "ROMA17")
		)
		(pad "N19" smd circle
			(at 5.999988 1.199896 180)
			(size 0.3556 0.3556)
			(layers "F.Cu" "F.Mask" "F.Paste")
			(net "ROMA18")
		)
		(pad "N20" smd circle
			(at 6.800088 1.199896 180)
			(size 0.3556 0.3556)
			(layers "F.Cu" "F.Mask" "F.Paste")
			(net "ROMA21")
		)
		(pad "N21" smd circle
			(at 7.599934 1.199896 180)
			(size 0.3556 0.3556)
			(layers "F.Cu" "F.Mask" "F.Paste")
			(net "TP_BMC_GPIOR5")
		)
		(pad "N22" smd circle
			(at 8.400034 1.199896 180)
			(size 0.3556 0.3556)
			(layers "F.Cu" "F.Mask" "F.Paste")
			(net "ROMA20")
		)
		(pad "P1" smd circle
			(at -8.400034 1.999996 180)
			(size 0.3556 0.3556)
			(layers "F.Cu" "F.Mask" "F.Paste")
			(net "P3V3_STBY")
		)
		(pad "P2" smd circle
			(at -7.599934 1.999996 180)
			(size 0.3556 0.3556)
			(layers "F.Cu" "F.Mask" "F.Paste")
			(net "ADCVREXT")
		)
		(pad "P3" smd circle
			(at -6.800088 1.999996 180)
			(size 0.3556 0.3556)
			(layers "F.Cu" "F.Mask" "F.Paste")
			(net "ADCAV33")
		)
		(pad "P4" smd circle
			(at -5.999988 1.999996 180)
			(size 0.3556 0.3556)
			(layers "F.Cu" "F.Mask" "F.Paste")
			(net "GND")
		)
		(pad "P5" smd circle
			(at -5.199888 1.999996 180)
			(size 0.3556 0.3556)
			(layers "F.Cu" "F.Mask" "F.Paste")
			(net "GND")
		)
		(pad "P6" smd circle
			(at -4.400042 1.999996 180)
			(size 0.3556 0.3556)
			(layers "F.Cu" "F.Mask" "F.Paste")
			(net "P1V26_STBY")
		)
		(pad "P9" smd circle
			(at -1.999996 1.999996 180)
			(size 0.3556 0.3556)
			(layers "F.Cu" "F.Mask" "F.Paste")
			(net "GND")
		)
		(pad "P10" smd circle
			(at -1.199896 1.999996 180)
			(size 0.3556 0.3556)
			(layers "F.Cu" "F.Mask" "F.Paste")
			(net "GND")
		)
		(pad "P11" smd circle
			(at -0.40005 1.999996 180)
			(size 0.3556 0.3556)
			(layers "F.Cu" "F.Mask" "F.Paste")
			(net "GND")
		)
		(pad "P12" smd circle
			(at 0.40005 1.999996 180)
			(size 0.3556 0.3556)
			(layers "F.Cu" "F.Mask" "F.Paste")
			(net "GND")
		)
		(pad "P13" smd circle
			(at 1.199896 1.999996 180)
			(size 0.3556 0.3556)
			(layers "F.Cu" "F.Mask" "F.Paste")
			(net "GND")
		)
		(pad "P14" smd circle
			(at 1.999996 1.999996 180)
			(size 0.3556 0.3556)
			(layers "F.Cu" "F.Mask" "F.Paste")
			(net "GND")
		)
		(pad "P17" smd circle
			(at 4.400042 1.999996 180)
			(size 0.3556 0.3556)
			(layers "F.Cu" "F.Mask" "F.Paste")
			(net "P1V26_STBY")
		)
		(pad "P18" smd circle
			(at 5.199888 1.999996 180)
			(size 0.3556 0.3556)
			(layers "F.Cu" "F.Mask" "F.Paste")
			(net "ROMA3")
		)
		(pad "P19" smd circle
			(at 5.999988 1.999996 180)
			(size 0.3556 0.3556)
			(layers "F.Cu" "F.Mask" "F.Paste")
			(net "ROMA4")
		)
		(pad "P20" smd circle
			(at 6.800088 1.999996 180)
			(size 0.3556 0.3556)
			(layers "F.Cu" "F.Mask" "F.Paste")
			(net "ROMA5")
		)
		(pad "P21" smd circle
			(at 7.599934 1.999996 180)
			(size 0.3556 0.3556)
			(layers "F.Cu" "F.Mask" "F.Paste")
			(net "ROMA6")
		)
		(pad "P22" smd circle
			(at 8.400034 1.999996 180)
			(size 0.3556 0.3556)
			(layers "F.Cu" "F.Mask" "F.Paste")
			(net "ROMA7")
		)
		(pad "R1" smd circle
			(at -8.400034 2.800096 180)
			(size 0.3556 0.3556)
			(layers "F.Cu" "F.Mask" "F.Paste")
			(net "DACRSET")
		)
		(pad "R2" smd circle
			(at -7.599934 2.800096 180)
			(size 0.3556 0.3556)
			(layers "F.Cu" "F.Mask" "F.Paste")
			(net "Net_1413")
		)
		(pad "R3" smd circle
			(at -6.800088 2.800096 180)
			(size 0.3556 0.3556)
			(layers "F.Cu" "F.Mask" "F.Paste")
			(net "Net_1412")
		)
		(pad "R4" smd circle
			(at -5.999988 2.800096 180)
			(size 0.3556 0.3556)
			(layers "F.Cu" "F.Mask" "F.Paste")
			(net "Net_1411")
		)
		(pad "R5" smd circle
			(at -5.199888 2.800096 180)
			(size 0.3556 0.3556)
			(layers "F.Cu" "F.Mask" "F.Paste")
			(net "GND")
		)
		(pad "R6" smd circle
			(at -4.400042 2.800096 180)
			(size 0.3556 0.3556)
			(layers "F.Cu" "F.Mask" "F.Paste")
			(net "P1V26_STBY")
		)
		(pad "R17" smd circle
			(at 4.400042 2.800096 180)
			(size 0.3556 0.3556)
			(layers "F.Cu" "F.Mask" "F.Paste")
			(net "P1V26_STBY")
		)
		(pad "R18" smd circle
			(at 5.199888 2.800096 180)
			(size 0.3556 0.3556)
			(layers "F.Cu" "F.Mask" "F.Paste")
			(net "TP_BMC_GPIOR4")
		)
		(pad "R19" smd circle
			(at 5.999988 2.800096 180)
			(size 0.3556 0.3556)
			(layers "F.Cu" "F.Mask" "F.Paste")
			(net "FLA_CS")
		)
		(pad "R20" smd circle
			(at 6.800088 2.800096 180)
			(size 0.3556 0.3556)
			(layers "F.Cu" "F.Mask" "F.Paste")
			(net "ROMA0")
		)
		(pad "R21" smd circle
			(at 7.599934 2.800096 180)
			(size 0.3556 0.3556)
			(layers "F.Cu" "F.Mask" "F.Paste")
			(net "ROMA1")
		)
		(pad "R22" smd circle
			(at 8.400034 2.800096 180)
			(size 0.3556 0.3556)
			(layers "F.Cu" "F.Mask" "F.Paste")
			(net "ROMA2")
		)
		(pad "T1" smd circle
			(at -8.400034 3.599942 180)
			(size 0.3556 0.3556)
			(layers "F.Cu" "F.Mask" "F.Paste")
			(net "TP_BMC_GPIOJ7")
		)
		(pad "T2" smd circle
			(at -7.599934 3.599942 180)
			(size 0.3556 0.3556)
			(layers "F.Cu" "F.Mask" "F.Paste")
			(net "TP_BMC_GPIOJ6")
		)
		(pad "T3" smd circle
			(at -6.800088 3.599942 180)
			(size 0.3556 0.3556)
			(layers "F.Cu" "F.Mask" "F.Paste")
			(net "P3V3_STBY")
		)
		(pad "T4" smd circle
			(at -5.999988 3.599942 180)
			(size 0.3556 0.3556)
			(layers "F.Cu" "F.Mask" "F.Paste")
			(net "TP_BMC_GPIOJ4")
		)
		(pad "T5" smd circle
			(at -5.199888 3.599942 180)
			(size 0.3556 0.3556)
			(layers "F.Cu" "F.Mask" "F.Paste")
			(net "TP_BMC_GPIOL1")
		)
		(pad "T18" smd circle
			(at 5.199888 3.599942 180)
			(size 0.3556 0.3556)
			(layers "F.Cu" "F.Mask" "F.Paste")
			(net "ROMA16")
		)
		(pad "T19" smd circle
			(at 5.999988 3.599942 180)
			(size 0.3556 0.3556)
			(layers "F.Cu" "F.Mask" "F.Paste")
			(net "ROMD5")
		)
		(pad "T20" smd circle
			(at 6.800088 3.599942 180)
			(size 0.3556 0.3556)
			(layers "F.Cu" "F.Mask" "F.Paste")
			(net "ROMD2")
		)
		(pad "T21" smd circle
			(at 7.599934 3.599942 180)
			(size 0.3556 0.3556)
			(layers "F.Cu" "F.Mask" "F.Paste")
			(net "ROMD1")
		)
		(pad "T22" smd circle
			(at 8.400034 3.599942 180)
			(size 0.3556 0.3556)
			(layers "F.Cu" "F.Mask" "F.Paste")
			(net "ROMD0")
		)
		(pad "U1" smd circle
			(at -8.400034 4.400042 180)
			(size 0.3556 0.3556)
			(layers "F.Cu" "F.Mask" "F.Paste")
			(net "TP_BMC_GPIOL0")
		)
		(pad "U2" smd circle
			(at -7.599934 4.400042 180)
			(size 0.3556 0.3556)
			(layers "F.Cu" "F.Mask" "F.Paste")
			(net "TP_BMC_GPIOJ5")
		)
		(pad "U3" smd circle
			(at -6.800088 4.400042 180)
			(size 0.3556 0.3556)
			(layers "F.Cu" "F.Mask" "F.Paste")
			(net "TP_BMC_GPIOL2")
		)
		(pad "U4" smd circle
			(at -5.999988 4.400042 180)
			(size 0.3556 0.3556)
			(layers "F.Cu" "F.Mask" "F.Paste")
			(net "TP_BMC_GPIOL4")
		)
		(pad "U5" smd circle
			(at -5.199888 4.400042 180)
			(size 0.3556 0.3556)
			(layers "F.Cu" "F.Mask" "F.Paste")
			(net "TP_BMC_GPIOL7")
		)
		(pad "U8" smd circle
			(at -2.800096 4.400042 180)
			(size 0.3556 0.3556)
			(layers "F.Cu" "F.Mask" "F.Paste")
			(net "P3V3_STBY")
		)
		(pad "U9" smd circle
			(at -1.999996 4.400042 180)
			(size 0.3556 0.3556)
			(layers "F.Cu" "F.Mask" "F.Paste")
			(net "P3V3_STBY")
		)
		(pad "U10" smd circle
			(at -1.199896 4.400042 180)
			(size 0.3556 0.3556)
			(layers "F.Cu" "F.Mask" "F.Paste")
			(net "P1V53_STBY")
		)
		(pad "U11" smd circle
			(at -0.40005 4.400042 180)
			(size 0.3556 0.3556)
			(layers "F.Cu" "F.Mask" "F.Paste")
			(net "P1V53_STBY")
		)
		(pad "U12" smd circle
			(at 0.40005 4.400042 180)
			(size 0.3556 0.3556)
			(layers "F.Cu" "F.Mask" "F.Paste")
			(net "P1V26_STBY")
		)
		(pad "U13" smd circle
			(at 1.199896 4.400042 180)
			(size 0.3556 0.3556)
			(layers "F.Cu" "F.Mask" "F.Paste")
			(net "P1V26_STBY")
		)
		(pad "U14" smd circle
			(at 1.999996 4.400042 180)
			(size 0.3556 0.3556)
			(layers "F.Cu" "F.Mask" "F.Paste")
			(net "P1V53_STBY")
		)
		(pad "U15" smd circle
			(at 2.800096 4.400042 180)
			(size 0.3556 0.3556)
			(layers "F.Cu" "F.Mask" "F.Paste")
			(net "P1V53_STBY")
		)
		(pad "U18" smd circle
			(at 5.199888 4.400042 180)
			(size 0.3556 0.3556)
			(layers "F.Cu" "F.Mask" "F.Paste")
			(net "EXP_TRAY_ID_BMC")
		)
		(pad "U19" smd circle
			(at 5.999988 4.400042 180)
			(size 0.3556 0.3556)
			(layers "F.Cu" "F.Mask" "F.Paste")
			(net "TP_BMC_GPIOR3")
		)
		(pad "U20" smd circle
			(at 6.800088 4.400042 180)
			(size 0.3556 0.3556)
			(layers "F.Cu" "F.Mask" "F.Paste")
			(net "ROMD7")
		)
		(pad "U21" smd circle
			(at 7.599934 4.400042 180)
			(size 0.3556 0.3556)
			(layers "F.Cu" "F.Mask" "F.Paste")
			(net "ROMD4")
		)
		(pad "U22" smd circle
			(at 8.400034 4.400042 180)
			(size 0.3556 0.3556)
			(layers "F.Cu" "F.Mask" "F.Paste")
			(net "ROMD3")
		)
		(pad "V1" smd circle
			(at -8.400034 5.199888 180)
			(size 0.3556 0.3556)
			(layers "F.Cu" "F.Mask" "F.Paste")
			(net "TP_BMC_GPIOL3")
		)
		(pad "V2" smd circle
			(at -7.599934 5.199888 180)
			(size 0.3556 0.3556)
			(layers "F.Cu" "F.Mask" "F.Paste")
			(net "TP_BMC_GPIOL5")
		)
	)
)
